%FSTAX23Y23*%
%MOIN*%
%SFA1B1*%

%IPPOS*%
%ADD13C,0.010000*%
%ADD17C,0.006000*%
%LNgrandmaster-1*%
%LPD*%
G54D13*
X0021Y0283D02*
D01*
X0021Y02834*
X00209Y02838*
X00209Y02842*
X00208Y02846*
X00206Y0285*
X00205Y02854*
X00203Y02858*
X00201Y02862*
X00198Y02865*
X00196Y02869*
X00193Y02872*
X0019Y02875*
X00187Y02878*
X00183Y0288*
X0018Y02882*
X00176Y02884*
X00172Y02886*
X00168Y02888*
X00164Y02889*
X0016Y0289*
X00155Y0289*
X00151Y02891*
X00147*
X00143Y0289*
X00138Y0289*
X00134Y02889*
X0013Y02888*
X00126Y02886*
X00122Y02884*
X00118Y02882*
X00115Y0288*
X00111Y02878*
X00108Y02875*
X00105Y02872*
X00102Y02869*
X001Y02865*
X00097Y02862*
X00095Y02858*
X00093Y02854*
X00092Y0285*
X0009Y02846*
X00089Y02842*
X00089Y02838*
X00088Y02834*
X00088Y0283*
X00088Y02825*
X00089Y02821*
X00089Y02817*
X0009Y02813*
X00092Y02809*
X00093Y02805*
X00095Y02801*
X00097Y02797*
X001Y02794*
X00102Y0279*
X00105Y02787*
X00108Y02784*
X00111Y02781*
X00115Y02779*
X00119Y02777*
X00122Y02775*
X00126Y02773*
X0013Y02772*
X00134Y0277*
X00138Y02769*
X00143Y02769*
X00147Y02769*
X00151*
X00155Y02769*
X0016Y02769*
X00164Y0277*
X00168Y02772*
X00172Y02773*
X00176Y02775*
X0018Y02777*
X00183Y02779*
X00187Y02781*
X0019Y02784*
X00193Y02787*
X00196Y0279*
X00198Y02794*
X00201Y02797*
X00203Y02801*
X00205Y02805*
X00206Y02809*
X00208Y02813*
X00209Y02817*
X00209Y02821*
X0021Y02825*
X0021Y0283*
X02592D02*
D01*
X02592Y02834*
X02591Y02838*
X02591Y02842*
X0259Y02846*
X02588Y0285*
X02587Y02854*
X02585Y02858*
X02583Y02862*
X0258Y02865*
X02578Y02869*
X02575Y02872*
X02572Y02875*
X02568Y02878*
X02565Y0288*
X02561Y02882*
X02558Y02884*
X02554Y02886*
X0255Y02888*
X02546Y02889*
X02541Y0289*
X02537Y0289*
X02533Y02891*
X02529*
X02525Y0289*
X0252Y0289*
X02516Y02889*
X02512Y02888*
X02508Y02886*
X02504Y02884*
X025Y02882*
X02497Y0288*
X02493Y02878*
X0249Y02875*
X02487Y02872*
X02484Y02869*
X02482Y02865*
X02479Y02862*
X02477Y02858*
X02475Y02854*
X02474Y0285*
X02472Y02846*
X02471Y02842*
X0247Y02838*
X0247Y02834*
X0247Y0283*
X0247Y02825*
X0247Y02821*
X02471Y02817*
X02472Y02813*
X02474Y02809*
X02475Y02805*
X02477Y02801*
X02479Y02797*
X02482Y02794*
X02484Y0279*
X02487Y02787*
X0249Y02784*
X02493Y02781*
X02497Y02779*
X025Y02777*
X02504Y02775*
X02508Y02773*
X02512Y02772*
X02516Y0277*
X0252Y02769*
X02525Y02769*
X02529Y02769*
X02533*
X02537Y02769*
X02541Y02769*
X02546Y0277*
X0255Y02772*
X02554Y02773*
X02558Y02775*
X02561Y02777*
X02565Y02779*
X02568Y02781*
X02572Y02784*
X02575Y02787*
X02578Y0279*
X0258Y02794*
X02583Y02797*
X02585Y02801*
X02587Y02805*
X02588Y02809*
X0259Y02813*
X02591Y02817*
X02591Y02821*
X02592Y02825*
X02592Y0283*
Y03853D02*
D01*
X02592Y03857*
X02591Y03862*
X02591Y03866*
X0259Y0387*
X02588Y03874*
X02587Y03878*
X02585Y03882*
X02583Y03886*
X0258Y03889*
X02578Y03892*
X02575Y03896*
X02572Y03899*
X02568Y03901*
X02565Y03904*
X02561Y03906*
X02558Y03908*
X02554Y0391*
X0255Y03911*
X02546Y03912*
X02541Y03913*
X02537Y03914*
X02533Y03914*
X02529*
X02525Y03914*
X0252Y03913*
X02516Y03912*
X02512Y03911*
X02508Y0391*
X02504Y03908*
X025Y03906*
X02497Y03904*
X02493Y03901*
X0249Y03899*
X02487Y03896*
X02484Y03892*
X02482Y03889*
X02479Y03886*
X02477Y03882*
X02475Y03878*
X02474Y03874*
X02472Y0387*
X02471Y03866*
X0247Y03862*
X0247Y03857*
X0247Y03853*
X0247Y03849*
X0247Y03845*
X02471Y0384*
X02472Y03836*
X02474Y03832*
X02475Y03828*
X02477Y03825*
X02479Y03821*
X02482Y03817*
X02484Y03814*
X02487Y03811*
X0249Y03808*
X02493Y03805*
X02497Y03803*
X025Y038*
X02504Y03798*
X02508Y03797*
X02512Y03795*
X02516Y03794*
X0252Y03793*
X02525Y03792*
X02529Y03792*
X02533*
X02537Y03792*
X02541Y03793*
X02546Y03794*
X0255Y03795*
X02554Y03797*
X02558Y03798*
X02561Y038*
X02565Y03803*
X02568Y03805*
X02572Y03808*
X02575Y03811*
X02578Y03814*
X0258Y03817*
X02583Y03821*
X02585Y03825*
X02587Y03828*
X02588Y03832*
X0259Y03836*
X02591Y0384*
X02591Y03845*
X02592Y03849*
X02592Y03853*
X00018Y03966D02*
X02662D01*
X00018Y02716D02*
Y03966D01*
Y02716D02*
X02662D01*
Y03966*
X02657Y04032D02*
Y04007D01*
X02652Y04002*
X02642*
X02637Y04007*
Y04032*
X02627Y04002D02*
X02617D01*
X02622*
Y04032*
X02627Y04027*
X02587Y04002D02*
Y04032D01*
X02602Y04017*
X02582*
X02258Y02948D02*
X02263Y02953D01*
X02273*
X02278Y02948*
Y02928*
X02273Y02923*
X02263*
X02258Y02928*
X02248Y02948D02*
X02243Y02953D01*
X02233*
X02228Y02948*
Y02943*
X02233Y02938*
X02228Y02933*
Y02928*
X02233Y02923*
X02243*
X02248Y02928*
Y02933*
X02243Y02938*
X02248Y02943*
Y02948*
X02243Y02938D02*
X02233D01*
X02218Y02953D02*
X02198D01*
Y02948*
X02218Y02928*
Y02923*
X02299Y02848D02*
X02304Y02853D01*
X02314*
X02319Y02848*
Y02828*
X02314Y02823*
X02304*
X02299Y02828*
X02289Y02848D02*
X02284Y02853D01*
X02274*
X02269Y02848*
Y02843*
X02274Y02838*
X02269Y02833*
Y02828*
X02274Y02823*
X02284*
X02289Y02828*
Y02833*
X02284Y02838*
X02289Y02843*
Y02848*
X02284Y02838D02*
X02274D01*
X02259Y02848D02*
X02254Y02853D01*
X02244*
X02239Y02848*
Y02843*
X02244Y02838*
X02239Y02833*
Y02828*
X02244Y02823*
X02254*
X02259Y02828*
Y02833*
X02254Y02838*
X02259Y02843*
Y02848*
X02254Y02838D02*
X02244D01*
X02629Y031D02*
X02634Y03095D01*
Y03085*
X02629Y0308*
X02609*
X02604Y03085*
Y03095*
X02609Y031*
X02629Y0311D02*
X02634Y03115D01*
Y03125*
X02629Y0313*
X02624*
X02619Y03125*
X02614Y0313*
X02609*
X02604Y03125*
Y03115*
X02609Y0311*
X02614*
X02619Y03115*
X02624Y0311*
X02629*
X02619Y03115D02*
Y03125D01*
X02609Y0314D02*
X02604Y03145D01*
Y03155*
X02609Y0316*
X02629*
X02634Y03155*
Y03145*
X02629Y0314*
X02624*
X02619Y03145*
Y0316*
X02849Y03022D02*
X02854Y03027D01*
X02864*
X02869Y03022*
Y03002*
X02864Y02997*
X02854*
X02849Y03002*
X02839D02*
X02834Y02997D01*
X02824*
X02819Y03002*
Y03022*
X02824Y03027*
X02834*
X02839Y03022*
Y03017*
X02834Y03012*
X02819*
X02809Y03022D02*
X02804Y03027D01*
X02794*
X02789Y03022*
Y03002*
X02794Y02997*
X02804*
X02809Y03002*
Y03022*
X0305Y00461D02*
X03055Y00456D01*
Y00446*
X0305Y00441*
X0303*
X03025Y00446*
Y00456*
X0303Y00461*
X03055Y00491D02*
Y00471D01*
X0304*
X03045Y00481*
Y00486*
X0304Y00491*
X0303*
X03025Y00486*
Y00476*
X0303Y00471*
X0305Y00501D02*
X03055Y00506D01*
Y00516*
X0305Y00521*
X03045*
X0304Y00516*
Y00511*
Y00516*
X03035Y00521*
X0303*
X03025Y00516*
Y00506*
X0303Y00501*
X02984Y00461D02*
X02989Y00456D01*
Y00446*
X02984Y00441*
X02964*
X02959Y00446*
Y00456*
X02964Y00461*
X02989Y00491D02*
Y00471D01*
X02974*
X02979Y00481*
Y00486*
X02974Y00491*
X02964*
X02959Y00486*
Y00476*
X02964Y00471*
X02959Y00521D02*
Y00501D01*
X02979Y00521*
X02984*
X02989Y00516*
Y00506*
X02984Y00501*
X02889Y00461D02*
X02894Y00456D01*
Y00446*
X02889Y00441*
X02869*
X02864Y00446*
Y00456*
X02869Y00461*
X02894Y00491D02*
Y00471D01*
X02879*
X02884Y00481*
Y00486*
X02879Y00491*
X02869*
X02864Y00486*
Y00476*
X02869Y00471*
X02864Y00501D02*
Y00511D01*
Y00506*
X02894*
X02889Y00501*
X02818Y00461D02*
X02823Y00456D01*
Y00446*
X02818Y00441*
X02798*
X02793Y00446*
Y00456*
X02798Y00461*
X02823Y00491D02*
Y00471D01*
X02808*
X02813Y00481*
Y00486*
X02808Y00491*
X02798*
X02793Y00486*
Y00476*
X02798Y00471*
X02818Y00501D02*
X02823Y00506D01*
Y00516*
X02818Y00521*
X02798*
X02793Y00516*
Y00506*
X02798Y00501*
X02818*
X02727Y00461D02*
X02732Y00456D01*
Y00446*
X02727Y00441*
X02707*
X02702Y00446*
Y00456*
X02707Y00461*
X02702Y00486D02*
X02732D01*
X02717Y00471*
Y00491*
X02707Y00501D02*
X02702Y00506D01*
Y00516*
X02707Y00521*
X02727*
X02732Y00516*
Y00506*
X02727Y00501*
X02722*
X02717Y00506*
Y00521*
X02659Y00461D02*
X02664Y00456D01*
Y00446*
X02659Y00441*
X02639*
X02634Y00446*
Y00456*
X02639Y00461*
X02634Y00486D02*
X02664D01*
X02649Y00471*
Y00491*
X02659Y00501D02*
X02664Y00506D01*
Y00516*
X02659Y00521*
X02654*
X02649Y00516*
X02644Y00521*
X02639*
X02634Y00516*
Y00506*
X02639Y00501*
X02644*
X02649Y00506*
X02654Y00501*
X02659*
X02649Y00506D02*
Y00516D01*
X02544Y00461D02*
X02549Y00456D01*
Y00446*
X02544Y00441*
X02524*
X02519Y00446*
Y00456*
X02524Y00461*
X02519Y00486D02*
X02549D01*
X02534Y00471*
Y00491*
X02549Y00501D02*
Y00521D01*
X02544*
X02524Y00501*
X02519*
X02475Y00461D02*
X0248Y00456D01*
Y00446*
X02475Y00441*
X02455*
X0245Y00446*
Y00456*
X02455Y00461*
X0245Y00486D02*
X0248D01*
X02465Y00471*
Y00491*
X0248Y00521D02*
X02475Y00511D01*
X02465Y00501*
X02455*
X0245Y00506*
Y00516*
X02455Y00521*
X0246*
X02465Y00516*
Y00501*
X024Y00477D02*
X02405Y00472D01*
Y00462*
X024Y00457*
X0238*
X02375Y00462*
Y00472*
X0238Y00477*
X02375Y00502D02*
X02405D01*
X0239Y00487*
Y00507*
X02405Y00537D02*
Y00517D01*
X0239*
X02395Y00527*
Y00532*
X0239Y00537*
X0238*
X02375Y00532*
Y00522*
X0238Y00517*
X02331Y00479D02*
X02336Y00474D01*
Y00464*
X02331Y00459*
X02311*
X02306Y00464*
Y00474*
X02311Y00479*
X02306Y00504D02*
X02336D01*
X02321Y00489*
Y00509*
X02306Y00534D02*
X02336D01*
X02321Y00519*
Y00539*
G54D17*
X02594Y02977D02*
Y03037D01*
X0267Y02977D02*
Y03037D01*
X02332Y02906D02*
X02392D01*
X02332Y02982D02*
X02392D01*
M02*